(kicad_pcb
	(version 20260206)
	(generator "pcbnew")
	(generator_version "10.0")
	(general
		(thickness 1.6)
		(legacy_teardrops no)
	)
	(paper "A4")
	(title_block
		(title "01162023_DA0F0TEBIF0_F0T_Expander_BD_F_brd_V02_OCP.brd")
		(comment 1 "Grand Teton / footprints 9209-9216 of 9728")
	)
	(layers
		(0 "F.Cu" signal "TOP")
		(4 "In1.Cu" signal "GND")
		(6 "In2.Cu" signal "VCC")
		(8 "In3.Cu" signal "VCC1")
		(10 "In4.Cu" signal "GND1")
		(12 "In5.Cu" signal "IN1")
		(14 "In6.Cu" signal "GND2")
		(16 "In7.Cu" signal "IN2")
		(18 "In8.Cu" signal "GND3")
		(20 "In9.Cu" signal "IN3")
		(22 "In10.Cu" signal "GND4")
		(24 "In11.Cu" signal "IN4")
		(26 "In12.Cu" signal "GND5")
		(28 "In13.Cu" signal "IN5")
		(30 "In14.Cu" signal "GND6")
		(32 "In15.Cu" signal "IN6")
		(34 "In16.Cu" signal "GND7")
		(2 "B.Cu" signal "BOTTOM")
		(9 "F.Adhes" user "F.Adhesive")
		(11 "B.Adhes" user "B.Adhesive")
		(13 "F.Paste" user "Package Geometry/Pastemask Top")
		(15 "B.Paste" user "Package Geometry/Pastemask Bottom")
		(5 "F.SilkS" user "Ref Des/Silkscreen Top")
		(7 "B.SilkS" user "Ref Des/Silkscreen Bottom")
		(1 "F.Mask" user "Board Geometry/Soldermask Top")
		(3 "B.Mask" user "Board Geometry/Soldermask Bottom")
		(17 "Dwgs.User" user "User.Drawings")
		(19 "Cmts.User" user "User.Comments")
		(21 "Eco1.User" user "User.Eco1")
		(23 "Eco2.User" user "User.Eco2")
		(25 "Edge.Cuts" user "Board Geometry/Outline")
		(27 "Margin" user)
		(31 "F.CrtYd" user "Package Geometry/Place Bound Top")
		(29 "B.CrtYd" user "Package Geometry/Place Bound Bottom")
		(35 "F.Fab" user "Ref Des/Assembly Top")
		(33 "B.Fab" user "Ref Des/Assembly Bottom")
	)
	(footprint ""
		(layer "B.Cu")
		(at 406.524968 -286.399732 90)
		(property "Reference" "C3473"
			(at 0 0 90)
			(layer "B.SilkS")
			(hide yes)
			(effects
				(font
					(size 1.27 1.27)
				)
				(justify mirror)
			)
		)
		(property "Value" ""
			(at 0 0 90)
			(layer "B.Fab")
			(effects
				(font
					(size 1.27 1.27)
				)
				(justify mirror)
			)
		)
		(duplicate_pad_numbers_are_jumpers no)
		(fp_line
			(start 0.299974 -0.150114)
			(end -0.299974 -0.150114)
			(stroke
				(width 0.1)
				(type default)
			)
			(layer "B.Fab")
		)
		(fp_line
			(start -0.299974 -0.150114)
			(end -0.299974 0.150114)
			(stroke
				(width 0.1)
				(type default)
			)
			(layer "B.Fab")
		)
		(fp_line
			(start 0.299974 0.150114)
			(end 0.299974 -0.150114)
			(stroke
				(width 0.1)
				(type default)
			)
			(layer "B.Fab")
		)
		(fp_line
			(start -0.299974 0.150114)
			(end 0.299974 0.150114)
			(stroke
				(width 0.1)
				(type default)
			)
			(layer "B.Fab")
		)
		(pad "1" smd rect
			(at 0.2667 0 270)
			(size 0.3048 0.381)
			(layers "B.Cu" "B.Mask" "B.Paste")
			(net "P1V25_SERDES_VDDPLL_PEX3")
		)
		(pad "2" smd rect
			(at -0.2667 0 270)
			(size 0.3048 0.381)
			(layers "B.Cu" "B.Mask" "B.Paste")
			(net "GND")
		)
	)
	(footprint ""
		(layer "B.Cu")
		(at 46.355 -293.52494)
		(property "Reference" "C3057"
			(at 0 0 0)
			(layer "B.SilkS")
			(hide yes)
			(effects
				(font
					(size 1.27 1.27)
				)
				(justify mirror)
			)
		)
		(property "Value" ""
			(at 0 0 0)
			(layer "B.Fab")
			(effects
				(font
					(size 1.27 1.27)
				)
				(justify mirror)
			)
		)
		(duplicate_pad_numbers_are_jumpers no)
		(fp_line
			(start -0.299974 -0.150114)
			(end -0.299974 0.150114)
			(stroke
				(width 0.1)
				(type default)
			)
			(layer "B.Fab")
		)
		(fp_line
			(start -0.299974 0.150114)
			(end 0.299974 0.150114)
			(stroke
				(width 0.1)
				(type default)
			)
			(layer "B.Fab")
		)
		(fp_line
			(start 0.299974 -0.150114)
			(end -0.299974 -0.150114)
			(stroke
				(width 0.1)
				(type default)
			)
			(layer "B.Fab")
		)
		(fp_line
			(start 0.299974 0.150114)
			(end 0.299974 -0.150114)
			(stroke
				(width 0.1)
				(type default)
			)
			(layer "B.Fab")
		)
		(pad "1" smd rect
			(at 0.2667 0 180)
			(size 0.3048 0.381)
			(layers "B.Cu" "B.Mask" "B.Paste")
			(net "PCEPLL6_VDDA18_PEX0")
		)
		(pad "2" smd rect
			(at -0.2667 0 180)
			(size 0.3048 0.381)
			(layers "B.Cu" "B.Mask" "B.Paste")
			(net "GND")
		)
	)
	(footprint ""
		(layer "B.Cu")
		(at 69.24929 -115.613434 -90)
		(property "Reference" "U13"
			(at -1.805686 4.416806 0)
			(unlocked yes)
			(layer "B.SilkS")
			(effects
				(font
					(size 0.7874 0.5842)
					(thickness 0.1524)
				)
				(justify mirror)
			)
		)
		(property "Value" ""
			(at 0 0 90)
			(layer "B.Fab")
			(effects
				(font
					(size 1.27 1.27)
				)
				(justify mirror)
			)
		)
		(duplicate_pad_numbers_are_jumpers no)
		(fp_line
			(start -1.3462 1.1938)
			(end -1.3462 -1.1938)
			(stroke
				(width 0.1524)
				(type default)
			)
			(layer "B.SilkS")
		)
		(fp_line
			(start 1.3462 1.1938)
			(end -1.3462 1.1938)
			(stroke
				(width 0.1524)
				(type default)
			)
			(layer "B.SilkS")
		)
		(fp_line
			(start -1.3462 -1.1938)
			(end 1.3462 -1.1938)
			(stroke
				(width 0.1524)
				(type default)
			)
			(layer "B.SilkS")
		)
		(fp_line
			(start 1.3462 -1.1938)
			(end 1.3462 1.1684)
			(stroke
				(width 0.1524)
				(type default)
			)
			(layer "B.SilkS")
		)
		(fp_poly
			(pts
				(xy 1.447038 -0.760476) (xy 2.052066 -0.457962) (xy 2.052066 -1.06299)
			)
			(stroke
				(width 0)
				(type default)
			)
			(fill yes)
			(layer "B.SilkS")
		)
		(fp_line
			(start -0.674878 1.124966)
			(end -0.674878 -1.124966)
			(stroke
				(width 0.1)
				(type default)
			)
			(layer "B.Fab")
		)
		(fp_line
			(start 0.674878 1.124966)
			(end -0.674878 1.124966)
			(stroke
				(width 0.1)
				(type default)
			)
			(layer "B.Fab")
		)
		(fp_line
			(start -0.674878 -1.124966)
			(end 0.674878 -1.124966)
			(stroke
				(width 0.1)
				(type default)
			)
			(layer "B.Fab")
		)
		(fp_line
			(start 0.674878 -1.124966)
			(end 0.674878 1.124966)
			(stroke
				(width 0.1)
				(type default)
			)
			(layer "B.Fab")
		)
		(fp_poly
			(pts
				(xy 1.447038 -0.760476) (xy 2.052066 -0.457962) (xy 2.052066 -1.06299)
			)
			(stroke
				(width 0)
				(type default)
			)
			(fill yes)
			(layer "B.Fab")
		)
		(pad "1" smd rect
			(at 0.899922 -0.750062 90)
			(size 0.6096 0.6096)
			(layers "B.Cu" "B.Mask" "B.Paste")
			(net "NIC1_AUX_PWR_EN_R")
		)
		(pad "2" smd rect
			(at 0.899922 0)
			(size 0.4064 0.6096)
			(layers "B.Cu" "B.Mask" "B.Paste")
			(net "RST_SMB_NIC1_MUX_N")
		)
		(pad "3" smd rect
			(at 0.899922 0.750062 90)
			(size 0.6096 0.6096)
			(layers "B.Cu" "B.Mask" "B.Paste")
			(net "GND")
		)
		(pad "4" smd rect
			(at -0.899922 0.750062 90)
			(size 0.6096 0.6096)
			(layers "B.Cu" "B.Mask" "B.Paste")
			(net "RST_SMB_NIC1_MUX_ISO_N")
		)
		(pad "5" smd rect
			(at -0.899922 -0.750062 90)
			(size 0.6096 0.6096)
			(layers "B.Cu" "B.Mask" "B.Paste")
			(net "P3V3_AUX")
		)
	)
	(footprint ""
		(layer "B.Cu")
		(at 134.146544 -325.30923 -90)
		(property "Reference" "C4258"
			(at 0 0 90)
			(layer "B.SilkS")
			(hide yes)
			(effects
				(font
					(size 1.27 1.27)
				)
				(justify mirror)
			)
		)
		(property "Value" ""
			(at 0 0 90)
			(layer "B.Fab")
			(effects
				(font
					(size 1.27 1.27)
				)
				(justify mirror)
			)
		)
		(duplicate_pad_numbers_are_jumpers no)
		(fp_line
			(start -1.2954 0.5842)
			(end 1.2954 0.5842)
			(stroke
				(width 0.1524)
				(type default)
			)
			(layer "B.SilkS")
		)
		(fp_line
			(start 1.2954 0.5842)
			(end 1.2954 -0.5842)
			(stroke
				(width 0.1524)
				(type default)
			)
			(layer "B.SilkS")
		)
		(fp_line
			(start -1.2954 -0.5842)
			(end -1.2954 0.5842)
			(stroke
				(width 0.1524)
				(type default)
			)
			(layer "B.SilkS")
		)
		(fp_line
			(start 1.2954 -0.5842)
			(end -1.2954 -0.5842)
			(stroke
				(width 0.1524)
				(type default)
			)
			(layer "B.SilkS")
		)
		(fp_line
			(start -0.8636 0.4572)
			(end 0.8636 0.4572)
			(stroke
				(width 0.1)
				(type default)
			)
			(layer "B.Fab")
		)
		(fp_line
			(start 0.8636 0.4572)
			(end 0.8636 0.4064)
			(stroke
				(width 0.1)
				(type default)
			)
			(layer "B.Fab")
		)
		(fp_line
			(start -1.1938 0.4064)
			(end -0.8636 0.4064)
			(stroke
				(width 0.1)
				(type default)
			)
			(layer "B.Fab")
		)
		(fp_line
			(start -0.8636 0.4064)
			(end -0.8636 0.4572)
			(stroke
				(width 0.1)
				(type default)
			)
			(layer "B.Fab")
		)
		(fp_line
			(start 0.8636 0.4064)
			(end 1.1938 0.4064)
			(stroke
				(width 0.1)
				(type default)
			)
			(layer "B.Fab")
		)
		(fp_line
			(start 1.1938 0.4064)
			(end 1.1938 -0.4064)
			(stroke
				(width 0.1)
				(type default)
			)
			(layer "B.Fab")
		)
		(fp_line
			(start -1.1938 -0.4064)
			(end -1.1938 0.4064)
			(stroke
				(width 0.1)
				(type default)
			)
			(layer "B.Fab")
		)
		(fp_line
			(start -0.8636 -0.4064)
			(end -1.1938 -0.4064)
			(stroke
				(width 0.1)
				(type default)
			)
			(layer "B.Fab")
		)
		(fp_line
			(start 0.8636 -0.4064)
			(end 0.8636 -0.4572)
			(stroke
				(width 0.1)
				(type default)
			)
			(layer "B.Fab")
		)
		(fp_line
			(start 1.1938 -0.4064)
			(end 0.8636 -0.4064)
			(stroke
				(width 0.1)
				(type default)
			)
			(layer "B.Fab")
		)
		(fp_line
			(start -0.8636 -0.4572)
			(end -0.8636 -0.4064)
			(stroke
				(width 0.1)
				(type default)
			)
			(layer "B.Fab")
		)
		(fp_line
			(start 0.8636 -0.4572)
			(end -0.8636 -0.4572)
			(stroke
				(width 0.1)
				(type default)
			)
			(layer "B.Fab")
		)
		(pad "1" smd rect
			(at 0.7366 0 180)
			(size 0.7112 0.8128)
			(layers "B.Cu" "B.Mask" "B.Paste")
			(net "P0V8_SERDES_VDDA_PEX1_C4")
		)
		(pad "2" smd rect
			(at -0.7366 0 180)
			(size 0.7112 0.8128)
			(layers "B.Cu" "B.Mask" "B.Paste")
			(net "GND")
		)
	)
	(footprint ""
		(layer "B.Cu")
		(at 113.561114 -258.004564 90)
		(property "Reference" "PR96"
			(at 0 0 90)
			(layer "B.SilkS")
			(hide yes)
			(effects
				(font
					(size 1.27 1.27)
				)
				(justify mirror)
			)
		)
		(property "Value" ""
			(at 0 0 90)
			(layer "B.Fab")
			(effects
				(font
					(size 1.27 1.27)
				)
				(justify mirror)
			)
		)
		(duplicate_pad_numbers_are_jumpers no)
		(fp_line
			(start 0.7874 -0.4064)
			(end -0.7874 -0.4064)
			(stroke
				(width 0.1524)
				(type default)
			)
			(layer "B.SilkS")
		)
		(fp_line
			(start -0.7874 -0.4064)
			(end -0.7874 0.4064)
			(stroke
				(width 0.1524)
				(type default)
			)
			(layer "B.SilkS")
		)
		(fp_line
			(start 0.7874 0.4064)
			(end 0.7874 -0.4064)
			(stroke
				(width 0.1524)
				(type default)
			)
			(layer "B.SilkS")
		)
		(fp_line
			(start -0.7874 0.4064)
			(end 0.7874 0.4064)
			(stroke
				(width 0.1524)
				(type default)
			)
			(layer "B.SilkS")
		)
		(fp_line
			(start 0.67945 -0.305054)
			(end 0.12065 -0.305054)
			(stroke
				(width 0.1)
				(type default)
			)
			(layer "B.Fab")
		)
		(fp_line
			(start 0.12065 -0.305054)
			(end 0.12065 -0.2794)
			(stroke
				(width 0.1)
				(type default)
			)
			(layer "B.Fab")
		)
		(fp_line
			(start -0.12065 -0.3048)
			(end -0.67945 -0.3048)
			(stroke
				(width 0.1)
				(type default)
			)
			(layer "B.Fab")
		)
		(fp_line
			(start -0.67945 -0.3048)
			(end -0.67945 0.3048)
			(stroke
				(width 0.1)
				(type default)
			)
			(layer "B.Fab")
		)
		(fp_line
			(start 0.12065 -0.2794)
			(end -0.12065 -0.2794)
			(stroke
				(width 0.1)
				(type default)
			)
			(layer "B.Fab")
		)
		(fp_line
			(start -0.12065 -0.2794)
			(end -0.12065 -0.3048)
			(stroke
				(width 0.1)
				(type default)
			)
			(layer "B.Fab")
		)
		(fp_line
			(start 0.12065 0.2794)
			(end 0.12065 0.3048)
			(stroke
				(width 0.1)
				(type default)
			)
			(layer "B.Fab")
		)
		(fp_line
			(start -0.120396 0.2794)
			(end 0.12065 0.2794)
			(stroke
				(width 0.1)
				(type default)
			)
			(layer "B.Fab")
		)
		(fp_line
			(start 0.67945 0.3048)
			(end 0.67945 -0.305054)
			(stroke
				(width 0.1)
				(type default)
			)
			(layer "B.Fab")
		)
		(fp_line
			(start 0.12065 0.3048)
			(end 0.67945 0.3048)
			(stroke
				(width 0.1)
				(type default)
			)
			(layer "B.Fab")
		)
		(fp_line
			(start -0.120396 0.3048)
			(end -0.120396 0.2794)
			(stroke
				(width 0.1)
				(type default)
			)
			(layer "B.Fab")
		)
		(fp_line
			(start -0.67945 0.3048)
			(end -0.120396 0.3048)
			(stroke
				(width 0.1)
				(type default)
			)
			(layer "B.Fab")
		)
		(pad "1" smd circle
			(at 0.40005 0 270)
			(size 0 0)
			(layers "B.Cu" "B.Mask" "B.Paste")
			(net "P5V_AUX")
		)
		(pad "2" smd circle
			(at -0.40005 0 270)
			(size 0 0)
			(layers "B.Cu" "B.Mask" "B.Paste")
			(net "P0V8_PEX0_IINSEN")
		)
	)
	(footprint ""
		(layer "B.Cu")
		(at 149.352254 -209.562192 -90)
		(property "Reference" "R971"
			(at 0 0 90)
			(layer "B.SilkS")
			(hide yes)
			(effects
				(font
					(size 1.27 1.27)
				)
				(justify mirror)
			)
		)
		(property "Value" ""
			(at 0 0 90)
			(layer "B.Fab")
			(effects
				(font
					(size 1.27 1.27)
				)
				(justify mirror)
			)
		)
		(duplicate_pad_numbers_are_jumpers no)
		(fp_line
			(start -0.7874 0.4064)
			(end 0.7874 0.4064)
			(stroke
				(width 0.1524)
				(type default)
			)
			(layer "B.SilkS")
		)
		(fp_line
			(start 0.7874 0.4064)
			(end 0.7874 -0.4064)
			(stroke
				(width 0.1524)
				(type default)
			)
			(layer "B.SilkS")
		)
		(fp_line
			(start -0.7874 -0.4064)
			(end -0.7874 0.4064)
			(stroke
				(width 0.1524)
				(type default)
			)
			(layer "B.SilkS")
		)
		(fp_line
			(start 0.7874 -0.4064)
			(end -0.7874 -0.4064)
			(stroke
				(width 0.1524)
				(type default)
			)
			(layer "B.SilkS")
		)
		(fp_line
			(start -0.67945 0.3048)
			(end -0.120396 0.3048)
			(stroke
				(width 0.1)
				(type default)
			)
			(layer "B.Fab")
		)
		(fp_line
			(start -0.120396 0.3048)
			(end -0.120396 0.2794)
			(stroke
				(width 0.1)
				(type default)
			)
			(layer "B.Fab")
		)
		(fp_line
			(start 0.12065 0.3048)
			(end 0.67945 0.3048)
			(stroke
				(width 0.1)
				(type default)
			)
			(layer "B.Fab")
		)
		(fp_line
			(start 0.67945 0.3048)
			(end 0.67945 -0.305054)
			(stroke
				(width 0.1)
				(type default)
			)
			(layer "B.Fab")
		)
		(fp_line
			(start -0.120396 0.2794)
			(end 0.12065 0.2794)
			(stroke
				(width 0.1)
				(type default)
			)
			(layer "B.Fab")
		)
		(fp_line
			(start 0.12065 0.2794)
			(end 0.12065 0.3048)
			(stroke
				(width 0.1)
				(type default)
			)
			(layer "B.Fab")
		)
		(fp_line
			(start -0.12065 -0.2794)
			(end -0.12065 -0.3048)
			(stroke
				(width 0.1)
				(type default)
			)
			(layer "B.Fab")
		)
		(fp_line
			(start 0.12065 -0.2794)
			(end -0.12065 -0.2794)
			(stroke
				(width 0.1)
				(type default)
			)
			(layer "B.Fab")
		)
		(fp_line
			(start -0.67945 -0.3048)
			(end -0.67945 0.3048)
			(stroke
				(width 0.1)
				(type default)
			)
			(layer "B.Fab")
		)
		(fp_line
			(start -0.12065 -0.3048)
			(end -0.67945 -0.3048)
			(stroke
				(width 0.1)
				(type default)
			)
			(layer "B.Fab")
		)
		(fp_line
			(start 0.12065 -0.305054)
			(end 0.12065 -0.2794)
			(stroke
				(width 0.1)
				(type default)
			)
			(layer "B.Fab")
		)
		(fp_line
			(start 0.67945 -0.305054)
			(end 0.12065 -0.305054)
			(stroke
				(width 0.1)
				(type default)
			)
			(layer "B.Fab")
		)
		(pad "1" smd circle
			(at 0.40005 0 90)
			(size 0 0)
			(layers "B.Cu" "B.Mask" "B.Paste")
			(net "UART_PEX0_CLI_BUF_RX")
		)
		(pad "2" smd circle
			(at -0.40005 0 90)
			(size 0 0)
			(layers "B.Cu" "B.Mask" "B.Paste")
			(net "P1V8_PEX")
		)
	)
	(footprint ""
		(layer "B.Cu")
		(at 191.920622 -114.35207 90)
		(property "Reference" "C900"
			(at 0 0 90)
			(layer "B.SilkS")
			(hide yes)
			(effects
				(font
					(size 1.27 1.27)
				)
				(justify mirror)
			)
		)
		(property "Value" ""
			(at 0 0 90)
			(layer "B.Fab")
			(effects
				(font
					(size 1.27 1.27)
				)
				(justify mirror)
			)
		)
		(duplicate_pad_numbers_are_jumpers no)
		(fp_line
			(start 0.7874 -0.4064)
			(end -0.7874 -0.4064)
			(stroke
				(width 0.1524)
				(type default)
			)
			(layer "B.SilkS")
		)
		(fp_line
			(start -0.7874 -0.4064)
			(end -0.7874 0.4064)
			(stroke
				(width 0.1524)
				(type default)
			)
			(layer "B.SilkS")
		)
		(fp_line
			(start 0.7874 0.4064)
			(end 0.7874 -0.4064)
			(stroke
				(width 0.1524)
				(type default)
			)
			(layer "B.SilkS")
		)
		(fp_line
			(start -0.7874 0.4064)
			(end 0.7874 0.4064)
			(stroke
				(width 0.1524)
				(type default)
			)
			(layer "B.SilkS")
		)
		(fp_line
			(start 0.67945 -0.305054)
			(end 0.12065 -0.305054)
			(stroke
				(width 0.1)
				(type default)
			)
			(layer "B.Fab")
		)
		(fp_line
			(start 0.12065 -0.305054)
			(end 0.12065 -0.2794)
			(stroke
				(width 0.1)
				(type default)
			)
			(layer "B.Fab")
		)
		(fp_line
			(start -0.12065 -0.3048)
			(end -0.67945 -0.3048)
			(stroke
				(width 0.1)
				(type default)
			)
			(layer "B.Fab")
		)
		(fp_line
			(start -0.67945 -0.3048)
			(end -0.67945 0.3048)
			(stroke
				(width 0.1)
				(type default)
			)
			(layer "B.Fab")
		)
		(fp_line
			(start 0.12065 -0.2794)
			(end -0.12065 -0.2794)
			(stroke
				(width 0.1)
				(type default)
			)
			(layer "B.Fab")
		)
		(fp_line
			(start -0.12065 -0.2794)
			(end -0.12065 -0.3048)
			(stroke
				(width 0.1)
				(type default)
			)
			(layer "B.Fab")
		)
		(fp_line
			(start 0.12065 0.2794)
			(end 0.12065 0.3048)
			(stroke
				(width 0.1)
				(type default)
			)
			(layer "B.Fab")
		)
		(fp_line
			(start -0.120396 0.2794)
			(end 0.12065 0.2794)
			(stroke
				(width 0.1)
				(type default)
			)
			(layer "B.Fab")
		)
		(fp_line
			(start 0.67945 0.3048)
			(end 0.67945 -0.305054)
			(stroke
				(width 0.1)
				(type default)
			)
			(layer "B.Fab")
		)
		(fp_line
			(start 0.12065 0.3048)
			(end 0.67945 0.3048)
			(stroke
				(width 0.1)
				(type default)
			)
			(layer "B.Fab")
		)
		(fp_line
			(start -0.120396 0.3048)
			(end -0.120396 0.2794)
			(stroke
				(width 0.1)
				(type default)
			)
			(layer "B.Fab")
		)
		(fp_line
			(start -0.67945 0.3048)
			(end -0.120396 0.3048)
			(stroke
				(width 0.1)
				(type default)
			)
			(layer "B.Fab")
		)
		(pad "1" smd circle
			(at 0.40005 0 270)
			(size 0 0)
			(layers "B.Cu" "B.Mask" "B.Paste")
			(net "P3V3_NIC3")
		)
		(pad "2" smd circle
			(at -0.40005 0 270)
			(size 0 0)
			(layers "B.Cu" "B.Mask" "B.Paste")
			(net "GND")
		)
	)
	(footprint ""
		(layer "B.Cu")
		(at 410.324808 -293.99992 -90)
		(property "Reference" "C1886"
			(at 0 0 90)
			(layer "B.SilkS")
			(hide yes)
			(effects
				(font
					(size 1.27 1.27)
				)
				(justify mirror)
			)
		)
		(property "Value" ""
			(at 0 0 90)
			(layer "B.Fab")
			(effects
				(font
					(size 1.27 1.27)
				)
				(justify mirror)
			)
		)
		(duplicate_pad_numbers_are_jumpers no)
		(fp_line
			(start -0.299974 0.150114)
			(end 0.299974 0.150114)
			(stroke
				(width 0.1)
				(type default)
			)
			(layer "B.Fab")
		)
		(fp_line
			(start 0.299974 0.150114)
			(end 0.299974 -0.150114)
			(stroke
				(width 0.1)
				(type default)
			)
			(layer "B.Fab")
		)
		(fp_line
			(start -0.299974 -0.150114)
			(end -0.299974 0.150114)
			(stroke
				(width 0.1)
				(type default)
			)
			(layer "B.Fab")
		)
		(fp_line
			(start 0.299974 -0.150114)
			(end -0.299974 -0.150114)
			(stroke
				(width 0.1)
				(type default)
			)
			(layer "B.Fab")
		)
		(pad "1" smd rect
			(at 0.2667 0 90)
			(size 0.3048 0.381)
			(layers "B.Cu" "B.Mask" "B.Paste")
			(net "P0V8_PEX3")
		)
		(pad "2" smd rect
			(at -0.2667 0 90)
			(size 0.3048 0.381)
			(layers "B.Cu" "B.Mask" "B.Paste")
			(net "GND")
		)
	)
)
